#ISCELL
  pure_quanta quanta_title_block_c *
  *
#ISCELL
  logical_power universal_gnd *
  page70_i1
#CELL
  pure_quanta socket4677_azif0045p001c01cs *
  page70_i2
#ISCELL
  logical_power universal_gnd *
  page70_i3
#ISCELL
  logical_power universal_gnd *
  page70_i4
#CELL
  pure_quanta socket4677_azif0045p001c01cs *
  page70_i5
#ISCELL
  logical_power universal_gnd *
  page70_i6
#ISCELL
  logical_power universal_gnd *
  page70_i7
#CELL
  pure_quanta socket4677_azif0045p001c01cs *
  page70_i8
#ISCELL
  logical_power universal_gnd *
  page70_i9
